FILE_TYPE = MULTI_PHYS_TABLE;

PART 'CONN_USB_14P_GH4_F_RA_TH'
CLASS = IO 

{========================================================================================}
: CLS_PN          | VALUE         =  JEDEC_TYPE                      | ALT_SYMBOLS                       | DESCRIPTION                                    			| CPN_STATUS;
{========================================================================================}
 'G200-13135-01'  |'2169890002'   = 'P_F_USB_2X7_GH4_RA_P035_PIH'    |'(P_F_USB_2X7_GH4_RA_P035_PIH)'    |'CON,14P,2X7,0.78MM PITCH,RCPT,USB2.0,TYPE C,RA,PIH,TH'   | ''

END_PART

END.

